# S9S_MB_2U (Grand Teton) — schematic netlist excerpt (pin names and nets, part order shuffled) for the footprints in the layout excerpt that follows; sources: Cadence DE-HDL packaged netlist, KiCad conversion of 03242023_DA0F0TMBIJ0_F0T_Motherboard_J_brd_V01_OCP.brd

C507  Q_CAP  47UF 4V 20% X6S  pkg C0805  page 76 : A = PVCCD_HV_CPU0 ; B = GND
R1  Q_RES  10 1% CHIP  pkg 0402LF  page 13 : A = H_CPU_PRDY_QS_GTL_N ; B = H_CPU0_PRDY_QS_GTL_R_N
R38  Q_RES  54.9K 1% CHIP  pkg 0402LF  page 94 : A = PD_CHG_CPU0_DIMM1_SAA ; B = GND

(kicad_pcb
	(version 20260206)
	(generator "pcbnew")
	(generator_version "10.0")
	(general
		(thickness 1.6)
		(legacy_teardrops no)
	)
	(paper "A4")
	(title_block
		(title "03242023_DA0F0TMBIJ0_F0T_Motherboard_J_brd_V01_OCP.brd")
		(comment 1 "Grand Teton / footprints 4620-4622 of 6105")
	)
	(layers
		(0 "F.Cu" signal "TOP")
		(4 "In1.Cu" signal "GND")
		(6 "In2.Cu" signal "IN1")
		(8 "In3.Cu" signal "GND1")
		(10 "In4.Cu" signal "IN2")
		(12 "In5.Cu" signal "GND2")
		(14 "In6.Cu" signal "IN3")
		(16 "In7.Cu" signal "GND3")
		(18 "In8.Cu" signal "VCC")
		(20 "In9.Cu" signal "VCC1")
		(22 "In10.Cu" signal "GND4")
		(24 "In11.Cu" signal "IN4")
		(26 "In12.Cu" signal "GND5")
		(28 "In13.Cu" signal "IN5")
		(30 "In14.Cu" signal "GND6")
		(32 "In15.Cu" signal "IN6")
		(34 "In16.Cu" signal "GND7")
		(2 "B.Cu" signal "BOTTOM")
		(9 "F.Adhes" user "F.Adhesive")
		(11 "B.Adhes" user "B.Adhesive")
		(13 "F.Paste" user "Package Geometry/Pastemask Top")
		(15 "B.Paste" user "Package Geometry/Pastemask Bottom")
		(5 "F.SilkS" user "Ref Des/Silkscreen Top")
		(7 "B.SilkS" user "Ref Des/Silkscreen Bottom")
		(1 "F.Mask" user "Board Geometry/Soldermask Top")
		(3 "B.Mask" user "Board Geometry/Soldermask Bottom")
		(17 "Dwgs.User" user "User.Drawings")
		(19 "Cmts.User" user "User.Comments")
		(21 "Eco1.User" user "User.Eco1")
		(23 "Eco2.User" user "User.Eco2")
		(25 "Edge.Cuts" user "Board Geometry/Outline")
		(27 "Margin" user)
		(31 "F.CrtYd" user "Package Geometry/Place Bound Top")
		(29 "B.CrtYd" user "Package Geometry/Place Bound Bottom")
		(35 "F.Fab" user "Ref Des/Assembly Top")
		(33 "B.Fab" user "Ref Des/Assembly Bottom")
	)
	(footprint ""
		(layer "B.Cu")
		(at 359.250742 -210.19389)
		(property "Reference" "C507"
			(at 0 0 0)
			(layer "B.SilkS")
			(hide yes)
			(effects
				(font
					(size 1.27 1.27)
				)
				(justify mirror)
			)
		)
		(property "Value" ""
			(at 0 0 0)
			(layer "B.Fab")
			(effects
				(font
					(size 1.27 1.27)
				)
				(justify mirror)
			)
		)
		(duplicate_pad_numbers_are_jumpers no)
		(fp_line
			(start -1.524 -0.762)
			(end -1.524 0.762)
			(stroke
				(width 0.1524)
				(type default)
			)
			(layer "B.SilkS")
		)
		(fp_line
			(start -1.524 0.762)
			(end 1.524 0.762)
			(stroke
				(width 0.1524)
				(type default)
			)
			(layer "B.SilkS")
		)
		(fp_line
			(start 1.524 -0.762)
			(end -1.524 -0.762)
			(stroke
				(width 0.1524)
				(type default)
			)
			(layer "B.SilkS")
		)
		(fp_line
			(start 1.524 0.762)
			(end 1.524 -0.762)
			(stroke
				(width 0.1524)
				(type default)
			)
			(layer "B.SilkS")
		)
		(fp_line
			(start -1.1049 -0.724916)
			(end 1.1049 -0.724916)
			(stroke
				(width 0.1)
				(type default)
			)
			(layer "B.Fab")
		)
		(fp_line
			(start -1.1049 0.724916)
			(end -1.1049 -0.724916)
			(stroke
				(width 0.1)
				(type default)
			)
			(layer "B.Fab")
		)
		(fp_line
			(start 1.1049 -0.724916)
			(end 1.1049 0.724916)
			(stroke
				(width 0.1)
				(type default)
			)
			(layer "B.Fab")
		)
		(fp_line
			(start 1.1049 0.724916)
			(end -1.1049 0.724916)
			(stroke
				(width 0.1)
				(type default)
			)
			(layer "B.Fab")
		)
		(pad "1" smd rect
			(at 0.889 0)
			(size 1.016 1.27)
			(layers "B.Cu" "B.Mask" "B.Paste")
			(net "PVCCD_HV_CPU0")
		)
		(pad "2" smd rect
			(at -0.889 0)
			(size 1.016 1.27)
			(layers "B.Cu" "B.Mask" "B.Paste")
			(net "GND")
		)
	)
	(footprint ""
		(layer "B.Cu")
		(at 446.179956 -318.603376)
		(property "Reference" "R38"
			(at 0 0 0)
			(layer "B.SilkS")
			(hide yes)
			(effects
				(font
					(size 1.27 1.27)
				)
				(justify mirror)
			)
		)
		(property "Value" ""
			(at 0 0 0)
			(layer "B.Fab")
			(effects
				(font
					(size 1.27 1.27)
				)
				(justify mirror)
			)
		)
		(duplicate_pad_numbers_are_jumpers no)
		(fp_line
			(start -0.7874 -0.4064)
			(end -0.7874 0.4064)
			(stroke
				(width 0.1524)
				(type default)
			)
			(layer "B.SilkS")
		)
		(fp_line
			(start -0.7874 0.4064)
			(end 0.7874 0.4064)
			(stroke
				(width 0.1524)
				(type default)
			)
			(layer "B.SilkS")
		)
		(fp_line
			(start 0.7874 -0.4064)
			(end -0.7874 -0.4064)
			(stroke
				(width 0.1524)
				(type default)
			)
			(layer "B.SilkS")
		)
		(fp_line
			(start 0.7874 0.4064)
			(end 0.7874 -0.4064)
			(stroke
				(width 0.1524)
				(type default)
			)
			(layer "B.SilkS")
		)
		(fp_line
			(start -0.67945 -0.3048)
			(end -0.67945 0.3048)
			(stroke
				(width 0.1)
				(type default)
			)
			(layer "B.Fab")
		)
		(fp_line
			(start -0.67945 0.3048)
			(end -0.120396 0.3048)
			(stroke
				(width 0.1)
				(type default)
			)
			(layer "B.Fab")
		)
		(fp_line
			(start -0.12065 -0.3048)
			(end -0.67945 -0.3048)
			(stroke
				(width 0.1)
				(type default)
			)
			(layer "B.Fab")
		)
		(fp_line
			(start -0.12065 -0.2794)
			(end -0.12065 -0.3048)
			(stroke
				(width 0.1)
				(type default)
			)
			(layer "B.Fab")
		)
		(fp_line
			(start -0.120396 0.2794)
			(end 0.12065 0.2794)
			(stroke
				(width 0.1)
				(type default)
			)
			(layer "B.Fab")
		)
		(fp_line
			(start -0.120396 0.3048)
			(end -0.120396 0.2794)
			(stroke
				(width 0.1)
				(type default)
			)
			(layer "B.Fab")
		)
		(fp_line
			(start 0.12065 -0.305054)
			(end 0.12065 -0.2794)
			(stroke
				(width 0.1)
				(type default)
			)
			(layer "B.Fab")
		)
		(fp_line
			(start 0.12065 -0.2794)
			(end -0.12065 -0.2794)
			(stroke
				(width 0.1)
				(type default)
			)
			(layer "B.Fab")
		)
		(fp_line
			(start 0.12065 0.2794)
			(end 0.12065 0.3048)
			(stroke
				(width 0.1)
				(type default)
			)
			(layer "B.Fab")
		)
		(fp_line
			(start 0.12065 0.3048)
			(end 0.67945 0.3048)
			(stroke
				(width 0.1)
				(type default)
			)
			(layer "B.Fab")
		)
		(fp_line
			(start 0.67945 -0.305054)
			(end 0.12065 -0.305054)
			(stroke
				(width 0.1)
				(type default)
			)
			(layer "B.Fab")
		)
		(fp_line
			(start 0.67945 0.3048)
			(end 0.67945 -0.305054)
			(stroke
				(width 0.1)
				(type default)
			)
			(layer "B.Fab")
		)
		(pad "1" smd circle
			(at 0.40005 0 180)
			(size 0 0)
			(layers "B.Cu" "B.Mask" "B.Paste")
			(net "PD_CHG_CPU0_DIMM1_SAA")
		)
		(pad "2" smd circle
			(at -0.40005 0 180)
			(size 0 0)
			(layers "B.Cu" "B.Mask" "B.Paste")
			(net "GND")
		)
	)
	(footprint ""
		(layer "B.Cu")
		(at 323.646292 -190.269114 -90)
		(property "Reference" "R1"
			(at 0 0 90)
			(layer "B.SilkS")
			(hide yes)
			(effects
				(font
					(size 1.27 1.27)
				)
				(justify mirror)
			)
		)
		(property "Value" ""
			(at 0 0 90)
			(layer "B.Fab")
			(effects
				(font
					(size 1.27 1.27)
				)
				(justify mirror)
			)
		)
		(duplicate_pad_numbers_are_jumpers no)
		(fp_line
			(start -0.7874 0.4064)
			(end 0.7874 0.4064)
			(stroke
				(width 0.1524)
				(type default)
			)
			(layer "B.SilkS")
		)
		(fp_line
			(start 0.7874 0.4064)
			(end 0.7874 -0.4064)
			(stroke
				(width 0.1524)
				(type default)
			)
			(layer "B.SilkS")
		)
		(fp_line
			(start -0.7874 -0.4064)
			(end -0.7874 0.4064)
			(stroke
				(width 0.1524)
				(type default)
			)
			(layer "B.SilkS")
		)
		(fp_line
			(start 0.7874 -0.4064)
			(end -0.7874 -0.4064)
			(stroke
				(width 0.1524)
				(type default)
			)
			(layer "B.SilkS")
		)
		(fp_line
			(start -0.67945 0.3048)
			(end -0.120396 0.3048)
			(stroke
				(width 0.1)
				(type default)
			)
			(layer "B.Fab")
		)
		(fp_line
			(start -0.120396 0.3048)
			(end -0.120396 0.2794)
			(stroke
				(width 0.1)
				(type default)
			)
			(layer "B.Fab")
		)
		(fp_line
			(start 0.12065 0.3048)
			(end 0.67945 0.3048)
			(stroke
				(width 0.1)
				(type default)
			)
			(layer "B.Fab")
		)
		(fp_line
			(start 0.67945 0.3048)
			(end 0.67945 -0.305054)
			(stroke
				(width 0.1)
				(type default)
			)
			(layer "B.Fab")
		)
		(fp_line
			(start -0.120396 0.2794)
			(end 0.12065 0.2794)
			(stroke
				(width 0.1)
				(type default)
			)
			(layer "B.Fab")
		)
		(fp_line
			(start 0.12065 0.2794)
			(end 0.12065 0.3048)
			(stroke
				(width 0.1)
				(type default)
			)
			(layer "B.Fab")
		)
		(fp_line
			(start -0.12065 -0.2794)
			(end -0.12065 -0.3048)
			(stroke
				(width 0.1)
				(type default)
			)
			(layer "B.Fab")
		)
		(fp_line
			(start 0.12065 -0.2794)
			(end -0.12065 -0.2794)
			(stroke
				(width 0.1)
				(type default)
			)
			(layer "B.Fab")
		)
		(fp_line
			(start -0.67945 -0.3048)
			(end -0.67945 0.3048)
			(stroke
				(width 0.1)
				(type default)
			)
			(layer "B.Fab")
		)
		(fp_line
			(start -0.12065 -0.3048)
			(end -0.67945 -0.3048)
			(stroke
				(width 0.1)
				(type default)
			)
			(layer "B.Fab")
		)
		(fp_line
			(start 0.12065 -0.305054)
			(end 0.12065 -0.2794)
			(stroke
				(width 0.1)
				(type default)
			)
			(layer "B.Fab")
		)
		(fp_line
			(start 0.67945 -0.305054)
			(end 0.12065 -0.305054)
			(stroke
				(width 0.1)
				(type default)
			)
			(layer "B.Fab")
		)
		(pad "1" smd circle
			(at 0.40005 0 90)
			(size 0 0)
			(layers "B.Cu" "B.Mask" "B.Paste")
			(net "H_CPU_PRDY_QS_GTL_N")
		)
		(pad "2" smd circle
			(at -0.40005 0 90)
			(size 0 0)
			(layers "B.Cu" "B.Mask" "B.Paste")
			(net "H_CPU0_PRDY_QS_GTL_R_N")
		)
	)
)
